FILE_TYPE=LIBRARY_PARTS;
primitive 'SW_H67881001','SW_H67881001_SM';
  pin
    'IO1':
      PIN_NUMBER='(1)';
      BIDIRECTIONAL='TRUE';
      INPUT_LOAD='(-0.01,0.01)';
      OUTPUT_LOAD='(1.0,-1.0)';
    'IO2':
      PIN_NUMBER='(2)';
      BIDIRECTIONAL='TRUE';
      INPUT_LOAD='(-0.01,0.01)';
      OUTPUT_LOAD='(1.0,-1.0)';
    'IO3':
      PIN_NUMBER='(3)';
      BIDIRECTIONAL='TRUE';
      INPUT_LOAD='(-0.01,0.01)';
      OUTPUT_LOAD='(1.0,-1.0)';
    'IO4':
      PIN_NUMBER='(4)';
      BIDIRECTIONAL='TRUE';
      INPUT_LOAD='(-0.01,0.01)';
      OUTPUT_LOAD='(1.0,-1.0)';
  end_pin;
  body
    PART_NAME='SW_H67881001';
    PHYS_DES_PREFIX='SW';
  end_body;
end_primitive;

END.
